(kicad_pcb
	(version 20260206)
	(generator "pcbnew")
	(generator_version "10.0")
	(general
		(thickness 1.6)
		(legacy_teardrops no)
	)
	(paper "A4")
	(title_block
		(title "Wiwynn_Tioga_Pass_MB.brd")
		(comment 1 "Tioga Pass / footprint 190 of 4770 (U2D1), pads 729-806 of 3647")
	)
	(layers
		(0 "F.Cu" signal "TOP")
		(4 "In1.Cu" signal "L2GND")
		(6 "In2.Cu" signal "L3")
		(8 "In3.Cu" signal "L4GND")
		(10 "In4.Cu" signal "L5")
		(12 "In5.Cu" signal "L6GND")
		(14 "In6.Cu" signal "L7VCC")
		(16 "In7.Cu" signal "L8VCC")
		(18 "In8.Cu" signal "L9GND")
		(20 "In9.Cu" signal "L10")
		(22 "In10.Cu" signal "L11GND")
		(24 "In11.Cu" signal "L12")
		(26 "In12.Cu" signal "L13GND")
		(2 "B.Cu" signal "BOTTOM")
		(9 "F.Adhes" user "F.Adhesive")
		(11 "B.Adhes" user "B.Adhesive")
		(13 "F.Paste" user "Package Geometry/Pastemask Top")
		(15 "B.Paste" user "Package Geometry/Pastemask Bottom")
		(5 "F.SilkS" user "Ref Des/Silkscreen Top")
		(7 "B.SilkS" user "Ref Des/Silkscreen Bottom")
		(1 "F.Mask" user "Board Geometry/Soldermask Top")
		(3 "B.Mask" user "Board Geometry/Soldermask Bottom")
		(17 "Dwgs.User" user "User.Drawings")
		(19 "Cmts.User" user "User.Comments")
		(21 "Eco1.User" user "User.Eco1")
		(23 "Eco2.User" user "User.Eco2")
		(25 "Edge.Cuts" user "Board Geometry/Outline")
		(27 "Margin" user)
		(31 "F.CrtYd" user "Package Geometry/Place Bound Top")
		(29 "B.CrtYd" user "Package Geometry/Place Bound Bottom")
		(35 "F.Fab" user "Ref Des/Assembly Top")
		(33 "B.Fab" user "Ref Des/Assembly Bottom")
	)
	(footprint ""
		(layer "F.Cu")
		(at 104.99979 -76.550012 180)
		(property "Reference" "U2D1"
			(at 25.19299 30.484318 0)
			(unlocked yes)
			(layer "F.SilkS")
			(effects
				(font
					(size 0.7874 0.5842)
					(thickness 0.1524)
				)
			)
		)
		(property "Value" ""
			(at 0 0 180)
			(layer "F.Fab")
			(effects
				(font
					(size 1.27 1.27)
				)
			)
		)
		(duplicate_pad_numbers_are_jumpers no)
		(pad "B11" smd circle
			(at -28.665424 -24.608028)
			(size 0.4318 0.4318)
			(layers "F.Cu" "F.Mask" "F.Paste")
			(net "PVPP_GHJ")
		)
		(pad "B13" smd circle
			(at -26.948384 -24.608028)
			(size 0.4318 0.4318)
			(layers "F.Cu" "F.Mask" "F.Paste")
			(net "P1V8_MCP_CPU1")
		)
		(pad "B15" smd circle
			(at -25.231598 -24.608028)
			(size 0.4318 0.4318)
			(layers "F.Cu" "F.Mask" "F.Paste")
			(net "P1V8_MCP_CPU1")
		)
		(pad "B17" smd custom
			(at -23.514558 -24.608028)
			(size 0.10795 0.10795)
			(layers "F.Cu" "F.Mask" "F.Paste")
			(net "P1V8_MCP_CPU1")
			(options
				(clearance outline)
				(anchor circle)
			)
			(primitives
				(gr_poly
					(pts
						(arc
							(start 0.2159 -0.0381)
							(mid 0 -0.254)
							(end -0.2159 -0.0381)
						)
						(arc
							(start -0.2159 0.0381)
							(mid 0 0.254)
							(end 0.2159 0.0381)
						)
					)
					(width 0)
					(fill yes)
				)
			)
		)
		(pad "B25" smd circle
			(at -16.646398 -24.608028)
			(size 0.4318 0.4318)
			(layers "F.Cu" "F.Mask" "F.Paste")
			(net "GND")
		)
		(pad "B27" smd circle
			(at -14.929612 -24.608028)
			(size 0.4318 0.4318)
			(layers "F.Cu" "F.Mask" "F.Paste")
			(net "M_H_DQ<54>")
		)
		(pad "B29" smd circle
			(at -13.212572 -24.608028)
			(size 0.4318 0.4318)
			(layers "F.Cu" "F.Mask" "F.Paste")
			(net "M_H_DQ<49>")
		)
		(pad "B31" smd circle
			(at -11.495532 -24.608028)
			(size 0.4318 0.4318)
			(layers "F.Cu" "F.Mask" "F.Paste")
			(net "GND")
		)
		(pad "B33" smd circle
			(at -9.778492 -24.608028)
			(size 0.4318 0.4318)
			(layers "F.Cu" "F.Mask" "F.Paste")
			(net "M_H_DQ<46>")
		)
		(pad "B35" smd circle
			(at -8.061452 -24.608028)
			(size 0.4318 0.4318)
			(layers "F.Cu" "F.Mask" "F.Paste")
			(net "M_H_DQ<41>")
		)
		(pad "B37" smd circle
			(at -6.344412 -24.608028)
			(size 0.4318 0.4318)
			(layers "F.Cu" "F.Mask" "F.Paste")
			(net "GND")
		)
		(pad "B39" smd circle
			(at -4.627626 -24.608028)
			(size 0.4318 0.4318)
			(layers "F.Cu" "F.Mask" "F.Paste")
			(net "M_G_DQ<38>")
		)
		(pad "B41" smd circle
			(at -2.910586 -24.608028)
			(size 0.4318 0.4318)
			(layers "F.Cu" "F.Mask" "F.Paste")
			(net "M_G_DQ<33>")
		)
		(pad "B43" smd custom
			(at -1.193546 -24.608028 315)
			(size 0.10795 0.10795)
			(layers "F.Cu" "F.Mask" "F.Paste")
			(net "GND")
			(options
				(clearance outline)
				(anchor circle)
			)
			(primitives
				(gr_poly
					(pts
						(arc
							(start 0.2159 -0.0381)
							(mid 0 -0.254)
							(end -0.2159 -0.0381)
						)
						(arc
							(start -0.2159 0.0381)
							(mid 0 0.254)
							(end 0.2159 0.0381)
						)
					)
					(width 0)
					(fill yes)
				)
			)
		)
		(pad "B47" smd custom
			(at 3.769106 -26.408126 45)
			(size 0.10795 0.10795)
			(layers "F.Cu" "F.Mask" "F.Paste")
			(net "PVDDQ_GHJ")
			(options
				(clearance outline)
				(anchor circle)
			)
			(primitives
				(gr_poly
					(pts
						(arc
							(start 0.2159 -0.0381)
							(mid 0 -0.254)
							(end -0.2159 -0.0381)
						)
						(arc
							(start -0.2159 0.0381)
							(mid 0 0.254)
							(end 0.2159 0.0381)
						)
					)
					(width 0)
					(fill yes)
				)
			)
		)
		(pad "B49" smd custom
			(at 5.485892 -26.408126)
			(size 0.10795 0.10795)
			(layers "F.Cu" "F.Mask" "F.Paste")
			(net "PVDDQ_GHJ")
			(options
				(clearance outline)
				(anchor circle)
			)
			(primitives
				(gr_poly
					(pts
						(arc
							(start 0.2159 -0.0381)
							(mid 0 -0.254)
							(end -0.2159 -0.0381)
						)
						(arc
							(start -0.2159 0.0381)
							(mid 0 0.254)
							(end 0.2159 0.0381)
						)
					)
					(width 0)
					(fill yes)
				)
			)
		)
		(pad "B51" smd custom
			(at 7.202932 -26.408126)
			(size 0.10795 0.10795)
			(layers "F.Cu" "F.Mask" "F.Paste")
			(net "M_G_CS_N<4>")
			(options
				(clearance outline)
				(anchor circle)
			)
			(primitives
				(gr_poly
					(pts
						(arc
							(start 0.2159 -0.0381)
							(mid 0 -0.254)
							(end -0.2159 -0.0381)
						)
						(arc
							(start -0.2159 0.0381)
							(mid 0 0.254)
							(end 0.2159 0.0381)
						)
					)
					(width 0)
					(fill yes)
				)
			)
		)
		(pad "B53" smd custom
			(at 8.919972 -26.408126)
			(size 0.10795 0.10795)
			(layers "F.Cu" "F.Mask" "F.Paste")
			(net "PVDDQ_GHJ")
			(options
				(clearance outline)
				(anchor circle)
			)
			(primitives
				(gr_poly
					(pts
						(arc
							(start 0.2159 -0.0381)
							(mid 0 -0.254)
							(end -0.2159 -0.0381)
						)
						(arc
							(start -0.2159 0.0381)
							(mid 0 0.254)
							(end 0.2159 0.0381)
						)
					)
					(width 0)
					(fill yes)
				)
			)
		)
		(pad "B55" smd custom
			(at 10.637012 -26.408126)
			(size 0.10795 0.10795)
			(layers "F.Cu" "F.Mask" "F.Paste")
			(net "M_G_CLK_DP<1>")
			(options
				(clearance outline)
				(anchor circle)
			)
			(primitives
				(gr_poly
					(pts
						(arc
							(start 0.2159 -0.0381)
							(mid 0 -0.254)
							(end -0.2159 -0.0381)
						)
						(arc
							(start -0.2159 0.0381)
							(mid 0 0.254)
							(end 0.2159 0.0381)
						)
					)
					(width 0)
					(fill yes)
				)
			)
		)
		(pad "B57" smd custom
			(at 12.354052 -26.408126)
			(size 0.10795 0.10795)
			(layers "F.Cu" "F.Mask" "F.Paste")
			(net "M_G_CLK_DP<3>")
			(options
				(clearance outline)
				(anchor circle)
			)
			(primitives
				(gr_poly
					(pts
						(arc
							(start 0.2159 -0.0381)
							(mid 0 -0.254)
							(end -0.2159 -0.0381)
						)
						(arc
							(start -0.2159 0.0381)
							(mid 0 0.254)
							(end 0.2159 0.0381)
						)
					)
					(width 0)
					(fill yes)
				)
			)
		)
		(pad "B59" smd custom
			(at 14.071092 -26.408126)
			(size 0.10795 0.10795)
			(layers "F.Cu" "F.Mask" "F.Paste")
			(net "PVDDQ_GHJ")
			(options
				(clearance outline)
				(anchor circle)
			)
			(primitives
				(gr_poly
					(pts
						(arc
							(start 0.2159 -0.0381)
							(mid 0 -0.254)
							(end -0.2159 -0.0381)
						)
						(arc
							(start -0.2159 0.0381)
							(mid 0 0.254)
							(end 0.2159 0.0381)
						)
					)
					(width 0)
					(fill yes)
				)
			)
		)
		(pad "B61" smd custom
			(at 15.787878 -26.408126)
			(size 0.10795 0.10795)
			(layers "F.Cu" "F.Mask" "F.Paste")
			(net "M_G_ALERT_N")
			(options
				(clearance outline)
				(anchor circle)
			)
			(primitives
				(gr_poly
					(pts
						(arc
							(start 0.2159 -0.0381)
							(mid 0 -0.254)
							(end -0.2159 -0.0381)
						)
						(arc
							(start -0.2159 0.0381)
							(mid 0 0.254)
							(end 0.2159 0.0381)
						)
					)
					(width 0)
					(fill yes)
				)
			)
		)
		(pad "B63" smd custom
			(at 17.504918 -26.408126)
			(size 0.10795 0.10795)
			(layers "F.Cu" "F.Mask" "F.Paste")
			(net "M_G_CKE<2>")
			(options
				(clearance outline)
				(anchor circle)
			)
			(primitives
				(gr_poly
					(pts
						(arc
							(start 0.2159 -0.0381)
							(mid 0 -0.254)
							(end -0.2159 -0.0381)
						)
						(arc
							(start -0.2159 0.0381)
							(mid 0 0.254)
							(end 0.2159 0.0381)
						)
					)
					(width 0)
					(fill yes)
				)
			)
		)
		(pad "B71" smd custom
			(at 24.373078 -26.408126)
			(size 0.10795 0.10795)
			(layers "F.Cu" "F.Mask" "F.Paste")
			(net "GND")
			(options
				(clearance outline)
				(anchor circle)
			)
			(primitives
				(gr_poly
					(pts
						(arc
							(start 0.2159 -0.0381)
							(mid 0 -0.254)
							(end -0.2159 -0.0381)
						)
						(arc
							(start -0.2159 0.0381)
							(mid 0 0.254)
							(end 0.2159 0.0381)
						)
					)
					(width 0)
					(fill yes)
				)
			)
		)
		(pad "B73" smd custom
			(at 26.090118 -26.408126)
			(size 0.10795 0.10795)
			(layers "F.Cu" "F.Mask" "F.Paste")
			(net "M_H_DQS_DN<12>")
			(options
				(clearance outline)
				(anchor circle)
			)
			(primitives
				(gr_poly
					(pts
						(arc
							(start 0.2159 -0.0381)
							(mid 0 -0.254)
							(end -0.2159 -0.0381)
						)
						(arc
							(start -0.2159 0.0381)
							(mid 0 0.254)
							(end 0.2159 0.0381)
						)
					)
					(width 0)
					(fill yes)
				)
			)
		)
		(pad "B75" smd custom
			(at 27.806904 -26.408126)
			(size 0.10795 0.10795)
			(layers "F.Cu" "F.Mask" "F.Paste")
			(net "GND")
			(options
				(clearance outline)
				(anchor circle)
			)
			(primitives
				(gr_poly
					(pts
						(arc
							(start 0.2159 -0.0381)
							(mid 0 -0.254)
							(end -0.2159 -0.0381)
						)
						(arc
							(start -0.2159 0.0381)
							(mid 0 0.254)
							(end 0.2159 0.0381)
						)
					)
					(width 0)
					(fill yes)
				)
			)
		)
		(pad "B77" smd custom
			(at 29.523944 -26.408126)
			(size 0.10795 0.10795)
			(layers "F.Cu" "F.Mask" "F.Paste")
			(net "TP_CPU1_RSVD_293")
			(options
				(clearance outline)
				(anchor circle)
			)
			(primitives
				(gr_poly
					(pts
						(arc
							(start 0.2159 -0.0381)
							(mid 0 -0.254)
							(end -0.2159 -0.0381)
						)
						(arc
							(start -0.2159 0.0381)
							(mid 0 0.254)
							(end 0.2159 0.0381)
						)
					)
					(width 0)
					(fill yes)
				)
			)
		)
		(pad "B79" smd custom
			(at 31.240984 -26.408126 315)
			(size 0.10795 0.10795)
			(layers "F.Cu" "F.Mask" "F.Paste")
			(net "GND")
			(options
				(clearance outline)
				(anchor circle)
			)
			(primitives
				(gr_poly
					(pts
						(arc
							(start 0.2159 -0.0381)
							(mid 0 -0.254)
							(end -0.2159 -0.0381)
						)
						(arc
							(start -0.2159 0.0381)
							(mid 0 0.254)
							(end 0.2159 0.0381)
						)
					)
					(width 0)
					(fill yes)
				)
			)
		)
		(pad "B81" smd custom
			(at 32.958024 -26.408126 315)
			(size 0.10795 0.10795)
			(layers "F.Cu" "F.Mask" "F.Paste")
			(net "TP_CPU1_RSVD_292")
			(options
				(clearance outline)
				(anchor circle)
			)
			(primitives
				(gr_poly
					(pts
						(arc
							(start 0.2159 -0.0381)
							(mid 0 -0.254)
							(end -0.2159 -0.0381)
						)
						(arc
							(start -0.2159 0.0381)
							(mid 0 0.254)
							(end 0.2159 0.0381)
						)
					)
					(width 0)
					(fill yes)
				)
			)
		)
		(pad "BA2" smd custom
			(at -36.392104 -5.291074 90)
			(size 0.10795 0.10795)
			(layers "F.Cu" "F.Mask" "F.Paste")
			(net "GND")
			(options
				(clearance outline)
				(anchor circle)
			)
			(primitives
				(gr_poly
					(pts
						(arc
							(start 0.2159 -0.0381)
							(mid 0 -0.254)
							(end -0.2159 -0.0381)
						)
						(arc
							(start -0.2159 0.0381)
							(mid 0 0.254)
							(end 0.2159 0.0381)
						)
					)
					(width 0)
					(fill yes)
				)
			)
		)
		(pad "BA4" smd circle
			(at -34.675064 -5.291074)
			(size 0.4318 0.4318)
			(layers "F.Cu" "F.Mask" "F.Paste")
			(net "UPI_CPU1_CPU0_P0P0_DP<16>")
		)
		(pad "BA6" smd circle
			(at -32.958024 -5.291074)
			(size 0.4318 0.4318)
			(layers "F.Cu" "F.Mask" "F.Paste")
			(net "GND")
		)
		(pad "BA8" smd circle
			(at -31.240984 -5.291074)
			(size 0.4318 0.4318)
			(layers "F.Cu" "F.Mask" "F.Paste")
			(net "UPI_CPU0_CPU1_P0P0_DN<13>")
		)
		(pad "BA10" smd circle
			(at -29.523944 -5.291074)
			(size 0.4318 0.4318)
			(layers "F.Cu" "F.Mask" "F.Paste")
			(net "UPI_CPU0_CPU1_P0P0_DN<19>")
		)
		(pad "BA12" smd circle
			(at -27.806904 -5.291074)
			(size 0.4318 0.4318)
			(layers "F.Cu" "F.Mask" "F.Paste")
			(net "GND")
		)
		(pad "BA14" smd circle
			(at -26.090118 -5.291074)
			(size 0.4318 0.4318)
			(layers "F.Cu" "F.Mask" "F.Paste")
			(net "TP_CPU1_RSVD_178")
		)
		(pad "BA16" smd circle
			(at -24.373078 -5.291074)
			(size 0.4318 0.4318)
			(layers "F.Cu" "F.Mask" "F.Paste")
			(net "TP_CPU1_RSVD_177")
		)
		(pad "BA18" smd circle
			(at -22.656038 -5.291074)
			(size 0.4318 0.4318)
			(layers "F.Cu" "F.Mask" "F.Paste")
			(net "TP_CPU1_RSVD_176")
		)
		(pad "BA20" smd circle
			(at -20.938998 -5.291074)
			(size 0.4318 0.4318)
			(layers "F.Cu" "F.Mask" "F.Paste")
			(net "PD_CPU1_BIST_ENABLE")
		)
		(pad "BA22" smd circle
			(at -19.221958 -5.291074)
			(size 0.4318 0.4318)
			(layers "F.Cu" "F.Mask" "F.Paste")
			(net "TP_CPU1_RSVD_175")
		)
		(pad "BA24" smd circle
			(at -17.504918 -5.291074)
			(size 0.4318 0.4318)
			(layers "F.Cu" "F.Mask" "F.Paste")
			(net "PVCCIO_CPU1")
		)
		(pad "BA26" smd circle
			(at -15.787878 -5.291074)
			(size 0.4318 0.4318)
			(layers "F.Cu" "F.Mask" "F.Paste")
			(net "PVCCIO_CPU1")
		)
		(pad "BA60" smd circle
			(at 14.929612 -7.091172)
			(size 0.508 0.508)
			(layers "F.Cu" "F.Mask" "F.Paste")
			(net "PVCCIN_CPU1")
		)
		(pad "BA62" smd circle
			(at 16.646398 -7.091172)
			(size 0.4318 0.4318)
			(layers "F.Cu" "F.Mask" "F.Paste")
			(net "GND")
		)
		(pad "BA64" smd circle
			(at 18.363438 -7.091172)
			(size 0.4318 0.4318)
			(layers "F.Cu" "F.Mask" "F.Paste")
			(net "TP_CPU1_RSVD_174")
		)
		(pad "BA66" smd circle
			(at 20.080478 -7.091172)
			(size 0.4318 0.4318)
			(layers "F.Cu" "F.Mask" "F.Paste")
			(net "TP_CPU1_RSVD_173")
		)
		(pad "BA68" smd circle
			(at 21.797518 -7.091172)
			(size 0.4318 0.4318)
			(layers "F.Cu" "F.Mask" "F.Paste")
			(net "GND")
		)
		(pad "BA70" smd circle
			(at 23.514558 -7.091172)
			(size 0.4318 0.4318)
			(layers "F.Cu" "F.Mask" "F.Paste")
			(net "M_J_ECC<7>")
		)
		(pad "BA72" smd circle
			(at 25.231598 -7.091172)
			(size 0.4318 0.4318)
			(layers "F.Cu" "F.Mask" "F.Paste")
			(net "M_J_ECC<1>")
		)
		(pad "BA74" smd circle
			(at 26.948384 -7.091172)
			(size 0.4318 0.4318)
			(layers "F.Cu" "F.Mask" "F.Paste")
			(net "GND")
		)
		(pad "BA76" smd circle
			(at 28.665424 -7.091172)
			(size 0.4318 0.4318)
			(layers "F.Cu" "F.Mask" "F.Paste")
			(net "TP_CPU1_RSVD_172")
		)
		(pad "BA78" smd circle
			(at 30.382464 -7.091172)
			(size 0.4318 0.4318)
			(layers "F.Cu" "F.Mask" "F.Paste")
			(net "TP_CPU1_RSVD_171")
		)
		(pad "BA80" smd circle
			(at 32.099504 -7.091172)
			(size 0.4318 0.4318)
			(layers "F.Cu" "F.Mask" "F.Paste")
			(net "GND")
		)
		(pad "BA82" smd circle
			(at 33.816544 -7.091172)
			(size 0.4318 0.4318)
			(layers "F.Cu" "F.Mask" "F.Paste")
			(net "TP_CPU1_RSVD_170")
		)
		(pad "BA84" smd circle
			(at 35.533584 -7.091172)
			(size 0.4318 0.4318)
			(layers "F.Cu" "F.Mask" "F.Paste")
			(net "GND")
		)
		(pad "BA86" smd custom
			(at 37.250624 -7.091172 270)
			(size 0.10795 0.10795)
			(layers "F.Cu" "F.Mask" "F.Paste")
			(net "VSENSE_PVCCIN_CPU1_SKT_VSEN")
			(options
				(clearance outline)
				(anchor circle)
			)
			(primitives
				(gr_poly
					(pts
						(arc
							(start 0.2159 -0.0381)
							(mid 0 -0.254)
							(end -0.2159 -0.0381)
						)
						(arc
							(start -0.2159 0.0381)
							(mid 0 0.254)
							(end 0.2159 0.0381)
						)
					)
					(width 0)
					(fill yes)
				)
			)
		)
		(pad "BB3" smd circle
			(at -35.533584 -4.796028)
			(size 0.4318 0.4318)
			(layers "F.Cu" "F.Mask" "F.Paste")
			(net "UPI_CPU1_CPU0_P0P0_DN<17>")
		)
		(pad "BB5" smd circle
			(at -33.816544 -4.796028)
			(size 0.4318 0.4318)
			(layers "F.Cu" "F.Mask" "F.Paste")
			(net "PVCCIO_CPU1")
		)
		(pad "BB7" smd circle
			(at -32.099504 -4.796028)
			(size 0.4318 0.4318)
			(layers "F.Cu" "F.Mask" "F.Paste")
			(net "UPI_CPU0_CPU1_P0P0_DN<14>")
		)
		(pad "BB9" smd circle
			(at -30.382464 -4.796028)
			(size 0.4318 0.4318)
			(layers "F.Cu" "F.Mask" "F.Paste")
			(net "UPI_CPU0_CPU1_P0P0_DP<17>")
		)
		(pad "BB11" smd circle
			(at -28.665424 -4.796028)
			(size 0.4318 0.4318)
			(layers "F.Cu" "F.Mask" "F.Paste")
			(net "UPI_CPU0_CPU1_P0P0_DP<19>")
		)
		(pad "BB13" smd circle
			(at -26.948384 -4.796028)
			(size 0.4318 0.4318)
			(layers "F.Cu" "F.Mask" "F.Paste")
			(net "TP_CPU1_RSVD_169")
		)
		(pad "BB15" smd circle
			(at -25.231598 -4.796028)
			(size 0.4318 0.4318)
			(layers "F.Cu" "F.Mask" "F.Paste")
			(net "TP_CPU1_RSVD_168")
		)
		(pad "BB17" smd circle
			(at -23.514558 -4.796028)
			(size 0.4318 0.4318)
			(layers "F.Cu" "F.Mask" "F.Paste")
			(net "TP_CPU1_RSVD_167")
		)
		(pad "BB19" smd circle
			(at -21.797518 -4.796028)
			(size 0.4318 0.4318)
			(layers "F.Cu" "F.Mask" "F.Paste")
			(net "GND")
		)
		(pad "BB21" smd circle
			(at -20.080478 -4.796028)
			(size 0.4318 0.4318)
			(layers "F.Cu" "F.Mask" "F.Paste")
			(net "TP_CPU1_RSVD_166")
		)
		(pad "BB23" smd circle
			(at -18.363438 -4.796028)
			(size 0.4318 0.4318)
			(layers "F.Cu" "F.Mask" "F.Paste")
			(net "GND")
		)
		(pad "BB25" smd circle
			(at -16.646398 -4.796028)
			(size 0.4318 0.4318)
			(layers "F.Cu" "F.Mask" "F.Paste")
			(net "CLK_100M_CPU1_RC_REFCLK1_DN")
		)
		(pad "BB27" smd circle
			(at -14.929612 -4.796028)
			(size 0.4318 0.4318)
			(layers "F.Cu" "F.Mask" "F.Paste")
			(net "PVCCIO_CPU1")
		)
		(pad "BB61" smd circle
			(at 15.787878 -6.596126)
			(size 0.4318 0.4318)
			(layers "F.Cu" "F.Mask" "F.Paste")
			(net "PVCCIN_CPU1")
		)
		(pad "BB63" smd circle
			(at 17.504918 -6.596126)
			(size 0.4318 0.4318)
			(layers "F.Cu" "F.Mask" "F.Paste")
			(net "GND")
		)
		(pad "BB65" smd circle
			(at 19.221958 -6.596126)
			(size 0.4318 0.4318)
			(layers "F.Cu" "F.Mask" "F.Paste")
			(net "TP_CPU1_RSVD_164")
		)
		(pad "BB67" smd circle
			(at 20.938998 -6.596126)
			(size 0.4318 0.4318)
			(layers "F.Cu" "F.Mask" "F.Paste")
			(net "TP_CPU1_RSVD_163")
		)
		(pad "BB69" smd circle
			(at 22.656038 -6.596126)
			(size 0.4318 0.4318)
			(layers "F.Cu" "F.Mask" "F.Paste")
			(net "GND")
		)
		(pad "BB71" smd circle
			(at 24.373078 -6.596126)
			(size 0.4318 0.4318)
			(layers "F.Cu" "F.Mask" "F.Paste")
			(net "M_J_DQS_DN<8>")
		)
		(pad "BB73" smd circle
			(at 26.090118 -6.596126)
			(size 0.4318 0.4318)
			(layers "F.Cu" "F.Mask" "F.Paste")
			(net "GND")
		)
		(pad "BB75" smd circle
			(at 27.806904 -6.596126)
			(size 0.4318 0.4318)
			(layers "F.Cu" "F.Mask" "F.Paste")
			(net "GND")
		)
		(pad "BB77" smd circle
			(at 29.523944 -6.596126)
			(size 0.4318 0.4318)
			(layers "F.Cu" "F.Mask" "F.Paste")
			(net "GND")
		)
	)
)
